# T6G (Grand Teton) — schematic netlist excerpt (pin names and nets, part order shuffled) for the footprints in the layout excerpt that follows; sources: Cadence DE-HDL packaged netlist, KiCad conversion of 04192023_DAF0TMB3IC0_F0TG_MB_C_brd_V02_OCP.brd

C2426  Q_CAP  22UF 4V 20% X6S  pkg C0402  page 74 : A = PVDDCR_SOC_P1 ; B = GND
R6759  Q_RES  0 5% CHIP  pkg 0201LF  page 184 : A = SMB_RT_CPU0_P3_SCL ; B = SMB_RT_CPU0_P3_R_SCL
C2111  Q_CAP  22UF 4V 20% X6S  pkg C0402  page 74 : A = PVDDIO_P1 ; B = GND

(kicad_pcb
	(version 20260206)
	(generator "pcbnew")
	(generator_version "10.0")
	(general
		(thickness 1.6)
		(legacy_teardrops no)
	)
	(paper "A4")
	(title_block
		(title "04192023_DAF0TMB3IC0_F0TG_MB_C_brd_V02_OCP.brd")
		(comment 1 "Grand Teton / footprints 7873-7875 of 8354")
	)
	(layers
		(0 "F.Cu" signal "TOP")
		(4 "In1.Cu" signal "GND")
		(6 "In2.Cu" signal "IN1")
		(8 "In3.Cu" signal "GND1")
		(10 "In4.Cu" signal "IN2")
		(12 "In5.Cu" signal "GND2")
		(14 "In6.Cu" signal "IN3")
		(16 "In7.Cu" signal "GND3")
		(18 "In8.Cu" signal "VCC")
		(20 "In9.Cu" signal "VCC1")
		(22 "In10.Cu" signal "GND4")
		(24 "In11.Cu" signal "IN4")
		(26 "In12.Cu" signal "GND5")
		(28 "In13.Cu" signal "IN5")
		(30 "In14.Cu" signal "GND6")
		(32 "In15.Cu" signal "IN6")
		(34 "In16.Cu" signal "GND7")
		(2 "B.Cu" signal "BOTTOM")
		(9 "F.Adhes" user "F.Adhesive")
		(11 "B.Adhes" user "B.Adhesive")
		(13 "F.Paste" user "Package Geometry/Pastemask Top")
		(15 "B.Paste" user "Package Geometry/Pastemask Bottom")
		(5 "F.SilkS" user "Ref Des/Silkscreen Top")
		(7 "B.SilkS" user "Ref Des/Silkscreen Bottom")
		(1 "F.Mask" user "Board Geometry/Soldermask Top")
		(3 "B.Mask" user "Board Geometry/Soldermask Bottom")
		(17 "Dwgs.User" user "User.Drawings")
		(19 "Cmts.User" user "User.Comments")
		(21 "Eco1.User" user "User.Eco1")
		(23 "Eco2.User" user "User.Eco2")
		(25 "Edge.Cuts" user "Board Geometry/Outline")
		(27 "Margin" user)
		(31 "F.CrtYd" user "Package Geometry/Place Bound Top")
		(29 "B.CrtYd" user "Package Geometry/Place Bound Bottom")
		(35 "F.Fab" user "Ref Des/Assembly Top")
		(33 "B.Fab" user "Ref Des/Assembly Bottom")
	)
	(footprint ""
		(layer "B.Cu")
		(at 105.960164 -257.455416 180)
		(property "Reference" "C2111"
			(at 0 0 0)
			(layer "B.SilkS")
			(hide yes)
			(effects
				(font
					(size 1.27 1.27)
				)
				(justify mirror)
			)
		)
		(property "Value" ""
			(at 0 0 0)
			(layer "B.Fab")
			(effects
				(font
					(size 1.27 1.27)
				)
				(justify mirror)
			)
		)
		(duplicate_pad_numbers_are_jumpers no)
		(fp_line
			(start 0.7874 0.4064)
			(end 0.7874 -0.4064)
			(stroke
				(width 0.1524)
				(type default)
			)
			(layer "B.SilkS")
		)
		(fp_line
			(start 0.7874 -0.4064)
			(end -0.7874 -0.4064)
			(stroke
				(width 0.1524)
				(type default)
			)
			(layer "B.SilkS")
		)
		(fp_line
			(start -0.7874 0.4064)
			(end 0.7874 0.4064)
			(stroke
				(width 0.1524)
				(type default)
			)
			(layer "B.SilkS")
		)
		(fp_line
			(start -0.7874 -0.4064)
			(end -0.7874 0.4064)
			(stroke
				(width 0.1524)
				(type default)
			)
			(layer "B.SilkS")
		)
		(fp_line
			(start 0.67945 0.3048)
			(end 0.67945 -0.305054)
			(stroke
				(width 0.1)
				(type default)
			)
			(layer "B.Fab")
		)
		(fp_line
			(start 0.67945 -0.305054)
			(end 0.12065 -0.305054)
			(stroke
				(width 0.1)
				(type default)
			)
			(layer "B.Fab")
		)
		(fp_line
			(start 0.12065 0.3048)
			(end 0.67945 0.3048)
			(stroke
				(width 0.1)
				(type default)
			)
			(layer "B.Fab")
		)
		(fp_line
			(start 0.12065 0.2794)
			(end 0.12065 0.3048)
			(stroke
				(width 0.1)
				(type default)
			)
			(layer "B.Fab")
		)
		(fp_line
			(start 0.12065 -0.2794)
			(end -0.12065 -0.2794)
			(stroke
				(width 0.1)
				(type default)
			)
			(layer "B.Fab")
		)
		(fp_line
			(start 0.12065 -0.305054)
			(end 0.12065 -0.2794)
			(stroke
				(width 0.1)
				(type default)
			)
			(layer "B.Fab")
		)
		(fp_line
			(start -0.120396 0.3048)
			(end -0.120396 0.2794)
			(stroke
				(width 0.1)
				(type default)
			)
			(layer "B.Fab")
		)
		(fp_line
			(start -0.120396 0.2794)
			(end 0.12065 0.2794)
			(stroke
				(width 0.1)
				(type default)
			)
			(layer "B.Fab")
		)
		(fp_line
			(start -0.12065 -0.2794)
			(end -0.12065 -0.3048)
			(stroke
				(width 0.1)
				(type default)
			)
			(layer "B.Fab")
		)
		(fp_line
			(start -0.12065 -0.3048)
			(end -0.67945 -0.3048)
			(stroke
				(width 0.1)
				(type default)
			)
			(layer "B.Fab")
		)
		(fp_line
			(start -0.67945 0.3048)
			(end -0.120396 0.3048)
			(stroke
				(width 0.1)
				(type default)
			)
			(layer "B.Fab")
		)
		(fp_line
			(start -0.67945 -0.3048)
			(end -0.67945 0.3048)
			(stroke
				(width 0.1)
				(type default)
			)
			(layer "B.Fab")
		)
		(pad "1" smd circle
			(at 0.40005 0)
			(size 0 0)
			(layers "B.Cu" "B.Mask" "B.Paste")
			(net "PVDDIO_P1")
		)
		(pad "2" smd circle
			(at -0.40005 0)
			(size 0 0)
			(layers "B.Cu" "B.Mask" "B.Paste")
			(net "GND")
		)
	)
	(footprint ""
		(layer "B.Cu")
		(at 229.8446 -336.296 180)
		(property "Reference" "R6759"
			(at 0 0 0)
			(layer "B.SilkS")
			(hide yes)
			(effects
				(font
					(size 1.27 1.27)
				)
				(justify mirror)
			)
		)
		(property "Value" ""
			(at 0 0 0)
			(layer "B.Fab")
			(effects
				(font
					(size 1.27 1.27)
				)
				(justify mirror)
			)
		)
		(duplicate_pad_numbers_are_jumpers no)
		(fp_line
			(start 0.32512 0.175006)
			(end 0.32512 -0.175006)
			(stroke
				(width 0.1)
				(type default)
			)
			(layer "B.Fab")
		)
		(fp_line
			(start 0.32512 -0.175006)
			(end -0.32512 -0.175006)
			(stroke
				(width 0.1)
				(type default)
			)
			(layer "B.Fab")
		)
		(fp_line
			(start -0.32512 0.175006)
			(end 0.32512 0.175006)
			(stroke
				(width 0.1)
				(type default)
			)
			(layer "B.Fab")
		)
		(fp_line
			(start -0.32512 -0.175006)
			(end -0.32512 0.175006)
			(stroke
				(width 0.1)
				(type default)
			)
			(layer "B.Fab")
		)
		(pad "1" smd rect
			(at 0.2667 0)
			(size 0.3048 0.381)
			(layers "B.Cu" "B.Mask" "B.Paste")
			(net "SMB_RT_CPU0_P3_SCL")
		)
		(pad "2" smd rect
			(at -0.2667 0 180)
			(size 0.3048 0.381)
			(layers "B.Cu" "B.Mask" "B.Paste")
			(net "SMB_RT_CPU0_P3_R_SCL")
		)
	)
	(footprint ""
		(layer "B.Cu")
		(at 115.610386 -253.432564)
		(property "Reference" "C2426"
			(at 0 0 0)
			(layer "B.SilkS")
			(hide yes)
			(effects
				(font
					(size 1.27 1.27)
				)
				(justify mirror)
			)
		)
		(property "Value" ""
			(at 0 0 0)
			(layer "B.Fab")
			(effects
				(font
					(size 1.27 1.27)
				)
				(justify mirror)
			)
		)
		(duplicate_pad_numbers_are_jumpers no)
		(fp_line
			(start -0.7874 -0.4064)
			(end -0.7874 0.4064)
			(stroke
				(width 0.1524)
				(type default)
			)
			(layer "B.SilkS")
		)
		(fp_line
			(start -0.7874 0.4064)
			(end 0.7874 0.4064)
			(stroke
				(width 0.1524)
				(type default)
			)
			(layer "B.SilkS")
		)
		(fp_line
			(start 0.7874 -0.4064)
			(end -0.7874 -0.4064)
			(stroke
				(width 0.1524)
				(type default)
			)
			(layer "B.SilkS")
		)
		(fp_line
			(start 0.7874 0.4064)
			(end 0.7874 -0.4064)
			(stroke
				(width 0.1524)
				(type default)
			)
			(layer "B.SilkS")
		)
		(fp_line
			(start -0.67945 -0.3048)
			(end -0.67945 0.3048)
			(stroke
				(width 0.1)
				(type default)
			)
			(layer "B.Fab")
		)
		(fp_line
			(start -0.67945 0.3048)
			(end -0.120396 0.3048)
			(stroke
				(width 0.1)
				(type default)
			)
			(layer "B.Fab")
		)
		(fp_line
			(start -0.12065 -0.3048)
			(end -0.67945 -0.3048)
			(stroke
				(width 0.1)
				(type default)
			)
			(layer "B.Fab")
		)
		(fp_line
			(start -0.12065 -0.2794)
			(end -0.12065 -0.3048)
			(stroke
				(width 0.1)
				(type default)
			)
			(layer "B.Fab")
		)
		(fp_line
			(start -0.120396 0.2794)
			(end 0.12065 0.2794)
			(stroke
				(width 0.1)
				(type default)
			)
			(layer "B.Fab")
		)
		(fp_line
			(start -0.120396 0.3048)
			(end -0.120396 0.2794)
			(stroke
				(width 0.1)
				(type default)
			)
			(layer "B.Fab")
		)
		(fp_line
			(start 0.12065 -0.305054)
			(end 0.12065 -0.2794)
			(stroke
				(width 0.1)
				(type default)
			)
			(layer "B.Fab")
		)
		(fp_line
			(start 0.12065 -0.2794)
			(end -0.12065 -0.2794)
			(stroke
				(width 0.1)
				(type default)
			)
			(layer "B.Fab")
		)
		(fp_line
			(start 0.12065 0.2794)
			(end 0.12065 0.3048)
			(stroke
				(width 0.1)
				(type default)
			)
			(layer "B.Fab")
		)
		(fp_line
			(start 0.12065 0.3048)
			(end 0.67945 0.3048)
			(stroke
				(width 0.1)
				(type default)
			)
			(layer "B.Fab")
		)
		(fp_line
			(start 0.67945 -0.305054)
			(end 0.12065 -0.305054)
			(stroke
				(width 0.1)
				(type default)
			)
			(layer "B.Fab")
		)
		(fp_line
			(start 0.67945 0.3048)
			(end 0.67945 -0.305054)
			(stroke
				(width 0.1)
				(type default)
			)
			(layer "B.Fab")
		)
		(pad "1" smd circle
			(at 0.40005 0 180)
			(size 0 0)
			(layers "B.Cu" "B.Mask" "B.Paste")
			(net "PVDDCR_SOC_P1")
		)
		(pad "2" smd circle
			(at -0.40005 0 180)
			(size 0 0)
			(layers "B.Cu" "B.Mask" "B.Paste")
			(net "GND")
		)
	)
)
